# T6G (Grand Teton) — schematic netlist excerpt (pin names and nets, part order shuffled) for the footprints in the layout excerpt that follows; sources: Cadence DE-HDL packaged netlist, KiCad conversion of 04192023_DAF0TMB3IC0_F0TG_MB_C_brd_V02_OCP.brd

R1444  Q_RES  130 1% CHIP  pkg 0402LF  page 165 : A = P3V3_AUX ; B = LED_BIOS_DBG_MODE_R
PC2103  Q_CAP  1UF 25V 10% X6S  pkg C0402  page 262 : A = HSC_VDD18 ; B = AGND_HSC
H30  HOLE  EMPTY  pkg TH  page 230 : \1\ = NC

(kicad_pcb
	(version 20260206)
	(generator "pcbnew")
	(generator_version "10.0")
	(general
		(thickness 1.6)
		(legacy_teardrops no)
	)
	(paper "A4")
	(title_block
		(title "04192023_DAF0TMB3IC0_F0TG_MB_C_brd_V02_OCP.brd")
		(comment 1 "Grand Teton / footprints 253-255 of 8354")
	)
	(layers
		(0 "F.Cu" signal "TOP")
		(4 "In1.Cu" signal "GND")
		(6 "In2.Cu" signal "IN1")
		(8 "In3.Cu" signal "GND1")
		(10 "In4.Cu" signal "IN2")
		(12 "In5.Cu" signal "GND2")
		(14 "In6.Cu" signal "IN3")
		(16 "In7.Cu" signal "GND3")
		(18 "In8.Cu" signal "VCC")
		(20 "In9.Cu" signal "VCC1")
		(22 "In10.Cu" signal "GND4")
		(24 "In11.Cu" signal "IN4")
		(26 "In12.Cu" signal "GND5")
		(28 "In13.Cu" signal "IN5")
		(30 "In14.Cu" signal "GND6")
		(32 "In15.Cu" signal "IN6")
		(34 "In16.Cu" signal "GND7")
		(2 "B.Cu" signal "BOTTOM")
		(9 "F.Adhes" user "F.Adhesive")
		(11 "B.Adhes" user "B.Adhesive")
		(13 "F.Paste" user "Package Geometry/Pastemask Top")
		(15 "B.Paste" user "Package Geometry/Pastemask Bottom")
		(5 "F.SilkS" user "Ref Des/Silkscreen Top")
		(7 "B.SilkS" user "Ref Des/Silkscreen Bottom")
		(1 "F.Mask" user "Board Geometry/Soldermask Top")
		(3 "B.Mask" user "Board Geometry/Soldermask Bottom")
		(17 "Dwgs.User" user "User.Drawings")
		(19 "Cmts.User" user "User.Comments")
		(21 "Eco1.User" user "User.Eco1")
		(23 "Eco2.User" user "User.Eco2")
		(25 "Edge.Cuts" user "Board Geometry/Outline")
		(27 "Margin" user)
		(31 "F.CrtYd" user "Package Geometry/Place Bound Top")
		(29 "B.CrtYd" user "Package Geometry/Place Bound Bottom")
		(35 "F.Fab" user "Ref Des/Assembly Top")
		(33 "B.Fab" user "Ref Des/Assembly Bottom")
	)
	(footprint ""
		(layer "F.Cu")
		(at 178.71694 -400.436842 180)
		(property "Reference" "PC2103"
			(at 0 0 180)
			(layer "F.SilkS")
			(hide yes)
			(effects
				(font
					(size 1.27 1.27)
				)
			)
		)
		(property "Value" ""
			(at 0 0 180)
			(layer "F.Fab")
			(effects
				(font
					(size 1.27 1.27)
				)
			)
		)
		(duplicate_pad_numbers_are_jumpers no)
		(fp_line
			(start 0.7874 0.4064)
			(end -0.7874 0.4064)
			(stroke
				(width 0.1524)
				(type default)
			)
			(layer "F.SilkS")
		)
		(fp_line
			(start 0.7874 -0.4064)
			(end 0.7874 0.4064)
			(stroke
				(width 0.1524)
				(type default)
			)
			(layer "F.SilkS")
		)
		(fp_line
			(start -0.7874 0.4064)
			(end -0.7874 -0.4064)
			(stroke
				(width 0.1524)
				(type default)
			)
			(layer "F.SilkS")
		)
		(fp_line
			(start -0.7874 -0.4064)
			(end 0.7874 -0.4064)
			(stroke
				(width 0.1524)
				(type default)
			)
			(layer "F.SilkS")
		)
		(fp_line
			(start 0.67945 0.3048)
			(end 0.120396 0.3048)
			(stroke
				(width 0.1)
				(type default)
			)
			(layer "F.Fab")
		)
		(fp_line
			(start 0.67945 -0.3048)
			(end 0.67945 0.3048)
			(stroke
				(width 0.1)
				(type default)
			)
			(layer "F.Fab")
		)
		(fp_line
			(start 0.12065 -0.2794)
			(end 0.12065 -0.3048)
			(stroke
				(width 0.1)
				(type default)
			)
			(layer "F.Fab")
		)
		(fp_line
			(start 0.12065 -0.3048)
			(end 0.67945 -0.3048)
			(stroke
				(width 0.1)
				(type default)
			)
			(layer "F.Fab")
		)
		(fp_line
			(start 0.120396 0.3048)
			(end 0.120396 0.2794)
			(stroke
				(width 0.1)
				(type default)
			)
			(layer "F.Fab")
		)
		(fp_line
			(start 0.120396 0.2794)
			(end -0.12065 0.2794)
			(stroke
				(width 0.1)
				(type default)
			)
			(layer "F.Fab")
		)
		(fp_line
			(start -0.12065 0.3048)
			(end -0.67945 0.3048)
			(stroke
				(width 0.1)
				(type default)
			)
			(layer "F.Fab")
		)
		(fp_line
			(start -0.12065 0.2794)
			(end -0.12065 0.3048)
			(stroke
				(width 0.1)
				(type default)
			)
			(layer "F.Fab")
		)
		(fp_line
			(start -0.12065 -0.2794)
			(end 0.12065 -0.2794)
			(stroke
				(width 0.1)
				(type default)
			)
			(layer "F.Fab")
		)
		(fp_line
			(start -0.12065 -0.305054)
			(end -0.12065 -0.2794)
			(stroke
				(width 0.1)
				(type default)
			)
			(layer "F.Fab")
		)
		(fp_line
			(start -0.67945 0.3048)
			(end -0.67945 -0.305054)
			(stroke
				(width 0.1)
				(type default)
			)
			(layer "F.Fab")
		)
		(fp_line
			(start -0.67945 -0.305054)
			(end -0.12065 -0.305054)
			(stroke
				(width 0.1)
				(type default)
			)
			(layer "F.Fab")
		)
		(pad "1" smd circle
			(at -0.40005 0 180)
			(size 0 0)
			(layers "F.Cu" "F.Mask" "F.Paste")
			(net "HSC_VDD18")
		)
		(pad "2" smd circle
			(at 0.40005 0 180)
			(size 0 0)
			(layers "F.Cu" "F.Mask" "F.Paste")
			(net "AGND_HSC")
		)
	)
	(footprint ""
		(layer "F.Cu")
		(at 8.081772 -361.761278)
		(property "Reference" "H30"
			(at 2.3114 1.940052 0)
			(unlocked yes)
			(layer "F.SilkS")
			(effects
				(font
					(size 0.7874 0.5842)
					(thickness 0.1524)
				)
				(justify left)
			)
		)
		(property "Value" ""
			(at 0 0 0)
			(layer "F.Fab")
			(effects
				(font
					(size 1.27 1.27)
				)
			)
		)
		(duplicate_pad_numbers_are_jumpers no)
		(fp_circle
			(center 0 0)
			(end 2.4003 0)
			(stroke
				(width 0.1524)
				(type default)
			)
			(fill no)
			(layer "F.SilkS")
		)
		(fp_circle
			(center 0 0)
			(end 6.5913 0)
			(stroke
				(width 0.1524)
				(type default)
			)
			(fill no)
			(layer "B.SilkS")
		)
		(fp_circle
			(center 0 0)
			(end 6.5913 0)
			(stroke
				(width 0.1)
				(type default)
			)
			(fill no)
			(layer "B.Fab")
		)
		(fp_circle
			(center 0 0)
			(end 2.4003 0)
			(stroke
				(width 0.1)
				(type default)
			)
			(fill no)
			(layer "F.Fab")
		)
		(pad "" np_thru_hole circle
			(at 0 0)
			(size 3.175 3.175)
			(drill 3.175)
			(layers "*.Cu" "*.Mask")
			(clearance 0.381)
			(thermal_gap 0.381)
		)
		(zone
			(layers "F.Cu" "B.Cu" "In1.Cu" "In2.Cu" "In3.Cu" "In4.Cu" "In5.Cu" "In6.Cu"
				"In7.Cu" "In8.Cu" "In9.Cu" "In10.Cu" "In11.Cu" "In12.Cu" "In13.Cu" "In14.Cu"
				"In15.Cu" "In16.Cu"
			)
			(hatch none 0.5)
			(connect_pads
				(clearance 0)
			)
			(min_thickness 0.25)
			(keepout
				(tracks not_allowed)
				(vias allowed)
				(pads allowed)
				(copperpour not_allowed)
				(footprints allowed)
			)
			(placement
				(enabled no)
				(sheetname "")
			)
			(fill
				(thermal_gap 0.5)
				(thermal_bridge_width 0.5)
				(island_removal_mode 0)
			)
			(polygon
				(pts
					(arc
						(start 10.177272 -361.761278)
						(mid 5.986272 -361.761278)
						(end 10.177272 -361.761278)
					)
				)
			)
		)
	)
	(footprint ""
		(layer "F.Cu")
		(at 335.28508 -15.996666 -90)
		(property "Reference" "R1444"
			(at 0 0 270)
			(layer "F.SilkS")
			(hide yes)
			(effects
				(font
					(size 1.27 1.27)
				)
			)
		)
		(property "Value" ""
			(at 0 0 270)
			(layer "F.Fab")
			(effects
				(font
					(size 1.27 1.27)
				)
			)
		)
		(duplicate_pad_numbers_are_jumpers no)
		(fp_line
			(start -0.7874 0.4064)
			(end -0.7874 -0.4064)
			(stroke
				(width 0.1524)
				(type default)
			)
			(layer "F.SilkS")
		)
		(fp_line
			(start 0.7874 0.4064)
			(end -0.7874 0.4064)
			(stroke
				(width 0.1524)
				(type default)
			)
			(layer "F.SilkS")
		)
		(fp_line
			(start -0.7874 -0.4064)
			(end 0.7874 -0.4064)
			(stroke
				(width 0.1524)
				(type default)
			)
			(layer "F.SilkS")
		)
		(fp_line
			(start 0.7874 -0.4064)
			(end 0.7874 0.4064)
			(stroke
				(width 0.1524)
				(type default)
			)
			(layer "F.SilkS")
		)
		(fp_line
			(start -0.67945 0.3048)
			(end -0.67945 -0.305054)
			(stroke
				(width 0.1)
				(type default)
			)
			(layer "F.Fab")
		)
		(fp_line
			(start -0.12065 0.3048)
			(end -0.67945 0.3048)
			(stroke
				(width 0.1)
				(type default)
			)
			(layer "F.Fab")
		)
		(fp_line
			(start 0.120396 0.3048)
			(end 0.120396 0.2794)
			(stroke
				(width 0.1)
				(type default)
			)
			(layer "F.Fab")
		)
		(fp_line
			(start 0.67945 0.3048)
			(end 0.120396 0.3048)
			(stroke
				(width 0.1)
				(type default)
			)
			(layer "F.Fab")
		)
		(fp_line
			(start -0.12065 0.2794)
			(end -0.12065 0.3048)
			(stroke
				(width 0.1)
				(type default)
			)
			(layer "F.Fab")
		)
		(fp_line
			(start 0.120396 0.2794)
			(end -0.12065 0.2794)
			(stroke
				(width 0.1)
				(type default)
			)
			(layer "F.Fab")
		)
		(fp_line
			(start -0.12065 -0.2794)
			(end 0.12065 -0.2794)
			(stroke
				(width 0.1)
				(type default)
			)
			(layer "F.Fab")
		)
		(fp_line
			(start 0.12065 -0.2794)
			(end 0.12065 -0.3048)
			(stroke
				(width 0.1)
				(type default)
			)
			(layer "F.Fab")
		)
		(fp_line
			(start 0.12065 -0.3048)
			(end 0.67945 -0.3048)
			(stroke
				(width 0.1)
				(type default)
			)
			(layer "F.Fab")
		)
		(fp_line
			(start 0.67945 -0.3048)
			(end 0.67945 0.3048)
			(stroke
				(width 0.1)
				(type default)
			)
			(layer "F.Fab")
		)
		(fp_line
			(start -0.67945 -0.305054)
			(end -0.12065 -0.305054)
			(stroke
				(width 0.1)
				(type default)
			)
			(layer "F.Fab")
		)
		(fp_line
			(start -0.12065 -0.305054)
			(end -0.12065 -0.2794)
			(stroke
				(width 0.1)
				(type default)
			)
			(layer "F.Fab")
		)
		(pad "1" smd circle
			(at -0.40005 0 270)
			(size 0 0)
			(layers "F.Cu" "F.Mask" "F.Paste")
			(net "P3V3_AUX")
		)
		(pad "2" smd circle
			(at 0.40005 0 270)
			(size 0 0)
			(layers "F.Cu" "F.Mask" "F.Paste")
			(net "LED_BIOS_DBG_MODE_R")
		)
	)
)
